(kicad_pcb
	(version 20260206)
	(generator "pcbnew")
	(generator_version "10.0")
	(general
		(thickness 1.6)
		(legacy_teardrops no)
	)
	(paper "A4")
	(title_block
		(title "Bryce Canyon_R.DPB_16317-1_OCP.brd")
		(comment 1 "Bryce Canyon / footprints 725-730 of 2099")
	)
	(layers
		(0 "F.Cu" signal "TOP")
		(4 "In1.Cu" signal "L2GND")
		(6 "In2.Cu" signal "L3")
		(8 "In3.Cu" signal "L4VCC")
		(10 "In4.Cu" signal "L5VCC")
		(12 "In5.Cu" signal "L6")
		(14 "In6.Cu" signal "L7GND")
		(2 "B.Cu" signal "BOTTOM")
		(9 "F.Adhes" user "F.Adhesive")
		(11 "B.Adhes" user "B.Adhesive")
		(13 "F.Paste" user "Package Geometry/Pastemask Top")
		(15 "B.Paste" user "Package Geometry/Pastemask Bottom")
		(5 "F.SilkS" user "Ref Des/Silkscreen Top")
		(7 "B.SilkS" user "Ref Des/Silkscreen Bottom")
		(1 "F.Mask" user "Board Geometry/Soldermask Top")
		(3 "B.Mask" user "Board Geometry/Soldermask Bottom")
		(17 "Dwgs.User" user "User.Drawings")
		(19 "Cmts.User" user "User.Comments")
		(21 "Eco1.User" user "User.Eco1")
		(23 "Eco2.User" user "User.Eco2")
		(25 "Edge.Cuts" user "Board Geometry/Outline")
		(27 "Margin" user)
		(31 "F.CrtYd" user "Package Geometry/Place Bound Top")
		(29 "B.CrtYd" user "Package Geometry/Place Bound Bottom")
		(35 "F.Fab" user "Ref Des/Assembly Top")
		(33 "B.Fab" user "Ref Des/Assembly Bottom")
	)
	(footprint ""
		(layer "F.Cu")
		(at 96.324928 -178.799998)
		(property "Reference" ""
			(at 0 0 0)
			(layer "F.SilkS")
			(hide yes)
			(effects
				(font
					(size 1.27 1.27)
				)
			)
		)
		(property "Value" "*"
			(at -8.398764 -8.057642 0)
			(unlocked yes)
			(layer "F.Fab")
			(hide yes)
			(effects
				(font
					(size 1.016 1.016)
					(thickness 0.1524)
				)
			)
		)
		(duplicate_pad_numbers_are_jumpers no)
		(fp_poly
			(pts
				(arc
					(start 7.3152 0)
					(mid 0 7.3152)
					(end -7.3152 0)
				)
				(arc
					(start -7.3152 -5.9944)
					(mid 0 -13.3096)
					(end 7.3152 -5.9944)
				)
			)
			(stroke
				(width 0)
				(type default)
			)
			(fill no)
			(layer "B.CrtYd")
		)
		(fp_poly
			(pts
				(arc
					(start 7.3152 0)
					(mid 0 7.3152)
					(end -7.3152 0)
				)
				(arc
					(start -7.3152 -5.9944)
					(mid 0 -13.3096)
					(end 7.3152 -5.9944)
				)
			)
			(stroke
				(width 0)
				(type default)
			)
			(fill no)
			(layer "F.CrtYd")
		)
		(fp_poly
			(pts
				(arc
					(start 7.3152 0)
					(mid 0 7.3152)
					(end -7.3152 0)
				)
				(arc
					(start -7.3152 -5.9944)
					(mid 0 -13.3096)
					(end 7.3152 -5.9944)
				)
			)
			(stroke
				(width 0)
				(type default)
			)
			(fill no)
			(layer "B.Fab")
		)
		(fp_poly
			(pts
				(arc
					(start 7.3152 0)
					(mid 0 7.3152)
					(end -7.3152 0)
				)
				(arc
					(start -7.3152 -5.9944)
					(mid 0 -13.3096)
					(end 7.3152 -5.9944)
				)
			)
			(stroke
				(width 0)
				(type default)
			)
			(fill no)
			(layer "F.Fab")
		)
		(pad "1" thru_hole oval
			(at 0 0)
			(size 14.0208 20.0152)
			(drill 0.0254
				(offset 0 -2.9972)
			)
			(layers "*.Cu" "*.Mask")
			(remove_unused_layers no)
			(net "Net_46")
			(clearance -1.002284)
			(thermal_gap 0.1524)
			(padstack
				(mode front_inner_back)
				(layer "Inner"
					(shape custom)
					(size 2.928012 2.928012)
					(options
						(anchor circle)
					)
					(primitives
						(gr_poly
							(pts
								(arc
									(start 4.571746 -2.084324)
									(mid 0.000333 7.430372)
									(end -4.571492 -2.084324)
								)
								(arc
									(start -4.571492 -2.084324)
									(mid -3.570296 -3.611977)
									(end -2.875026 -5.30098)
								)
								(arc
									(start -2.875026 -5.30098)
									(mid 0.000217 -7.43089)
									(end 2.87528 -5.30098)
								)
								(arc
									(start 2.87528 -5.30098)
									(mid 3.570511 -3.611956)
									(end 4.571746 -2.084324)
								)
							)
							(width 0)
							(fill yes)
						)
					)
					(clearance 0.1524)
				)
				(layer "B.Cu"
					(shape oval)
					(size 14.0208 20.0152)
					(offset 0 -2.9972)
					(clearance -1.002284)
				)
			)
		)
		(zone
			(layers "F.Cu" "B.Cu" "In1.Cu" "In2.Cu" "In3.Cu" "In4.Cu" "In5.Cu" "In6.Cu")
			(hatch none 0.5)
			(connect_pads
				(clearance 0)
			)
			(min_thickness 0.25)
			(keepout
				(tracks not_allowed)
				(vias allowed)
				(pads allowed)
				(copperpour not_allowed)
				(footprints allowed)
			)
			(placement
				(enabled no)
				(sheetname "")
			)
			(fill
				(thermal_gap 0.5)
				(thermal_bridge_width 0.5)
				(island_removal_mode 0)
			)
			(polygon
				(pts
					(arc
						(start 89.314528 -184.794398)
						(mid 96.324928 -191.804798)
						(end 103.335328 -184.794398)
					)
					(arc
						(start 103.335328 -178.799998)
						(mid 96.324928 -171.789598)
						(end 89.314528 -178.799998)
					)
				)
			)
		)
	)
	(footprint ""
		(layer "F.Cu")
		(at 130.4544 -32.8422 180)
		(property "Reference" "R695"
			(at 0 0 180)
			(layer "F.SilkS")
			(hide yes)
			(effects
				(font
					(size 1.27 1.27)
				)
			)
		)
		(property "Value" "220R3F-1-GP"
			(at -0.0254 -2.5146 180)
			(unlocked yes)
			(layer "F.Fab")
			(hide yes)
			(effects
				(font
					(size 1.016 1.016)
					(thickness 0.1524)
				)
			)
		)
		(property "Device Type" "R603H22"
			(at -0.0254 -4.0386 180)
			(unlocked yes)
			(layer "F.Fab")
			(hide yes)
			(effects
				(font
					(size 1.016 1.016)
					(thickness 0.1524)
				)
			)
		)
		(duplicate_pad_numbers_are_jumpers no)
		(fp_line
			(start 0.2032 0)
			(end 0.4826 0)
			(stroke
				(width 0.2032)
				(type default)
			)
			(layer "F.SilkS")
		)
		(fp_line
			(start -0.4826 0)
			(end -0.2032 0)
			(stroke
				(width 0.2032)
				(type default)
			)
			(layer "F.SilkS")
		)
		(fp_rect
			(start -0.5842 1.3335)
			(end 0.5842 -1.3335)
			(stroke
				(width 0)
				(type default)
			)
			(fill no)
			(layer "F.CrtYd")
		)
		(fp_rect
			(start -0.5842 1.3335)
			(end 0.5842 -1.3335)
			(stroke
				(width 0)
				(type default)
			)
			(fill no)
			(layer "F.Fab")
		)
		(pad "1" smd custom
			(at 0 -0.762 180)
			(size 0.2159 0.2159)
			(layers "F.Cu" "F.Mask" "F.Paste")
			(net "HDD_PRSNT_27")
			(options
				(clearance outline)
				(anchor circle)
			)
			(primitives
				(gr_poly
					(pts
						(arc
							(start -0.3302 -0.4318)
							(mid -0.402042 -0.402042)
							(end -0.4318 -0.3302)
						)
						(arc
							(start -0.4318 0.3302)
							(mid -0.402042 0.402042)
							(end -0.3302 0.4318)
						)
						(arc
							(start 0.3302 0.4318)
							(mid 0.402042 0.402042)
							(end 0.4318 0.3302)
						)
						(arc
							(start 0.4318 -0.3302)
							(mid 0.402042 -0.402042)
							(end 0.3302 -0.4318)
						)
					)
					(width 0)
					(fill yes)
				)
			)
		)
		(pad "2" smd custom
			(at 0 0.762 180)
			(size 0.2159 0.2159)
			(layers "F.Cu" "F.Mask" "F.Paste")
			(net "DRIVE_B_27_INS")
			(options
				(clearance outline)
				(anchor circle)
			)
			(primitives
				(gr_poly
					(pts
						(arc
							(start -0.3302 -0.4318)
							(mid -0.402042 -0.402042)
							(end -0.4318 -0.3302)
						)
						(arc
							(start -0.4318 0.3302)
							(mid -0.402042 0.402042)
							(end -0.3302 0.4318)
						)
						(arc
							(start 0.3302 0.4318)
							(mid 0.402042 0.402042)
							(end 0.4318 0.3302)
						)
						(arc
							(start 0.4318 -0.3302)
							(mid 0.402042 -0.402042)
							(end 0.3302 -0.4318)
						)
					)
					(width 0)
					(fill yes)
				)
			)
		)
	)
	(footprint ""
		(layer "F.Cu")
		(at 113.03 -214.249)
		(property "Reference" "R252"
			(at 0 0 0)
			(layer "F.SilkS")
			(hide yes)
			(effects
				(font
					(size 1.27 1.27)
				)
			)
		)
		(property "Value" "91R3F-1-GP"
			(at -0.0254 -2.5146 0)
			(unlocked yes)
			(layer "F.Fab")
			(hide yes)
			(effects
				(font
					(size 1.016 1.016)
					(thickness 0.1524)
				)
			)
		)
		(property "Device Type" "R603H22"
			(at -0.0254 -4.0386 0)
			(unlocked yes)
			(layer "F.Fab")
			(hide yes)
			(effects
				(font
					(size 1.016 1.016)
					(thickness 0.1524)
				)
			)
		)
		(duplicate_pad_numbers_are_jumpers no)
		(fp_line
			(start -0.4826 0)
			(end -0.2032 0)
			(stroke
				(width 0.2032)
				(type default)
			)
			(layer "F.SilkS")
		)
		(fp_line
			(start 0.2032 0)
			(end 0.4826 0)
			(stroke
				(width 0.2032)
				(type default)
			)
			(layer "F.SilkS")
		)
		(fp_rect
			(start -0.5842 1.3335)
			(end 0.5842 -1.3335)
			(stroke
				(width 0)
				(type default)
			)
			(fill no)
			(layer "F.CrtYd")
		)
		(fp_rect
			(start -0.5842 1.3335)
			(end 0.5842 -1.3335)
			(stroke
				(width 0)
				(type default)
			)
			(fill no)
			(layer "F.Fab")
		)
		(pad "1" smd custom
			(at 0 -0.762)
			(size 0.2159 0.2159)
			(layers "F.Cu" "F.Mask" "F.Paste")
			(net "P5V_B_1")
			(options
				(clearance outline)
				(anchor circle)
			)
			(primitives
				(gr_poly
					(pts
						(arc
							(start -0.3302 -0.4318)
							(mid -0.402042 -0.402042)
							(end -0.4318 -0.3302)
						)
						(arc
							(start -0.4318 0.3302)
							(mid -0.402042 0.402042)
							(end -0.3302 0.4318)
						)
						(arc
							(start 0.3302 0.4318)
							(mid 0.402042 0.402042)
							(end 0.4318 0.3302)
						)
						(arc
							(start 0.4318 -0.3302)
							(mid 0.402042 -0.402042)
							(end 0.3302 -0.4318)
						)
					)
					(width 0)
					(fill yes)
				)
			)
		)
		(pad "2" smd custom
			(at 0 0.762)
			(size 0.2159 0.2159)
			(layers "F.Cu" "F.Mask" "F.Paste")
			(net "DRV_ACT_3")
			(options
				(clearance outline)
				(anchor circle)
			)
			(primitives
				(gr_poly
					(pts
						(arc
							(start -0.3302 -0.4318)
							(mid -0.402042 -0.402042)
							(end -0.4318 -0.3302)
						)
						(arc
							(start -0.4318 0.3302)
							(mid -0.402042 0.402042)
							(end -0.3302 0.4318)
						)
						(arc
							(start 0.3302 0.4318)
							(mid 0.402042 0.402042)
							(end 0.4318 0.3302)
						)
						(arc
							(start 0.4318 -0.3302)
							(mid 0.402042 -0.402042)
							(end 0.3302 -0.4318)
						)
					)
					(width 0)
					(fill yes)
				)
			)
		)
	)
	(footprint ""
		(layer "F.Cu")
		(at 303.586896 -231.732074 90)
		(property "Reference" "R920"
			(at 0 0 90)
			(layer "F.SilkS")
			(hide yes)
			(effects
				(font
					(size 1.27 1.27)
				)
			)
		)
		(property "Value" "4K7R2F-GP"
			(at 0.064008 -3.993896 90)
			(unlocked yes)
			(layer "F.Fab")
			(hide yes)
			(effects
				(font
					(size 1.016 1.016)
					(thickness 0.1524)
				)
			)
		)
		(property "Device Type" "R402H16"
			(at 0.064008 -5.517896 90)
			(unlocked yes)
			(layer "F.Fab")
			(hide yes)
			(effects
				(font
					(size 1.016 1.016)
					(thickness 0.1524)
				)
			)
		)
		(duplicate_pad_numbers_are_jumpers no)
		(fp_line
			(start 0.508 -0.9398)
			(end -0.508 -0.9398)
			(stroke
				(width 0.1524)
				(type default)
			)
			(layer "F.SilkS")
		)
		(fp_line
			(start -0.508 -0.9398)
			(end -0.508 0.9398)
			(stroke
				(width 0.1524)
				(type default)
			)
			(layer "F.SilkS")
		)
		(fp_rect
			(start -0.508 0.9398)
			(end 0.508 -0.9398)
			(stroke
				(width 0)
				(type default)
			)
			(fill no)
			(layer "F.CrtYd")
		)
		(fp_rect
			(start -0.508 0.9398)
			(end 0.508 -0.9398)
			(stroke
				(width 0)
				(type default)
			)
			(fill no)
			(layer "F.Fab")
		)
		(pad "1" smd custom
			(at 0 -0.4445 90)
			(size 0.1397 0.1397)
			(layers "F.Cu" "F.Mask" "F.Paste")
			(net "SCC_B_SLOT_ID_0")
			(options
				(clearance outline)
				(anchor circle)
			)
			(primitives
				(gr_poly
					(pts
						(arc
							(start -0.1778 -0.2794)
							(mid -0.249642 -0.249642)
							(end -0.2794 -0.1778)
						)
						(arc
							(start -0.2794 0.1778)
							(mid -0.249642 0.249642)
							(end -0.1778 0.2794)
						)
						(arc
							(start 0.1778 0.2794)
							(mid 0.249642 0.249642)
							(end 0.2794 0.1778)
						)
						(arc
							(start 0.2794 -0.1778)
							(mid 0.249642 -0.249642)
							(end 0.1778 -0.2794)
						)
					)
					(width 0)
					(fill yes)
				)
			)
		)
		(pad "2" smd custom
			(at 0 0.4445 90)
			(size 0.1397 0.1397)
			(layers "F.Cu" "F.Mask" "F.Paste")
			(net "GND")
			(options
				(clearance outline)
				(anchor circle)
			)
			(primitives
				(gr_poly
					(pts
						(arc
							(start -0.1778 -0.2794)
							(mid -0.249642 -0.249642)
							(end -0.2794 -0.1778)
						)
						(arc
							(start -0.2794 0.1778)
							(mid -0.249642 0.249642)
							(end -0.1778 0.2794)
						)
						(arc
							(start 0.1778 0.2794)
							(mid 0.249642 0.249642)
							(end 0.2794 0.1778)
						)
						(arc
							(start 0.2794 -0.1778)
							(mid 0.249642 -0.249642)
							(end 0.1778 -0.2794)
						)
					)
					(width 0)
					(fill yes)
				)
			)
		)
	)
	(footprint ""
		(layer "F.Cu")
		(at 231.267 -197.612 -90)
		(property "Reference" "R77"
			(at 0 0 270)
			(layer "F.SilkS")
			(hide yes)
			(effects
				(font
					(size 1.27 1.27)
				)
			)
		)
		(property "Value" "4K7R2F-GP"
			(at 0.064008 -3.993896 270)
			(unlocked yes)
			(layer "F.Fab")
			(hide yes)
			(effects
				(font
					(size 1.016 1.016)
					(thickness 0.1524)
				)
			)
		)
		(property "Device Type" "R402H16"
			(at 0.064008 -5.517896 270)
			(unlocked yes)
			(layer "F.Fab")
			(hide yes)
			(effects
				(font
					(size 1.016 1.016)
					(thickness 0.1524)
				)
			)
		)
		(duplicate_pad_numbers_are_jumpers no)
		(fp_line
			(start -0.508 -0.9398)
			(end -0.508 0.9398)
			(stroke
				(width 0.1524)
				(type default)
			)
			(layer "F.SilkS")
		)
		(fp_line
			(start 0.508 -0.9398)
			(end -0.508 -0.9398)
			(stroke
				(width 0.1524)
				(type default)
			)
			(layer "F.SilkS")
		)
		(fp_rect
			(start -0.508 0.9398)
			(end 0.508 -0.9398)
			(stroke
				(width 0)
				(type default)
			)
			(fill no)
			(layer "F.CrtYd")
		)
		(fp_rect
			(start -0.508 0.9398)
			(end 0.508 -0.9398)
			(stroke
				(width 0)
				(type default)
			)
			(fill no)
			(layer "F.Fab")
		)
		(pad "1" smd custom
			(at 0 -0.4445 270)
			(size 0.1397 0.1397)
			(layers "F.Cu" "F.Mask" "F.Paste")
			(net "IO_EXP2_A0")
			(options
				(clearance outline)
				(anchor circle)
			)
			(primitives
				(gr_poly
					(pts
						(arc
							(start -0.1778 -0.2794)
							(mid -0.249642 -0.249642)
							(end -0.2794 -0.1778)
						)
						(arc
							(start -0.2794 0.1778)
							(mid -0.249642 0.249642)
							(end -0.1778 0.2794)
						)
						(arc
							(start 0.1778 0.2794)
							(mid 0.249642 0.249642)
							(end 0.2794 0.1778)
						)
						(arc
							(start 0.2794 -0.1778)
							(mid 0.249642 -0.249642)
							(end 0.1778 -0.2794)
						)
					)
					(width 0)
					(fill yes)
				)
			)
		)
		(pad "2" smd custom
			(at 0 0.4445 270)
			(size 0.1397 0.1397)
			(layers "F.Cu" "F.Mask" "F.Paste")
			(net "GND")
			(options
				(clearance outline)
				(anchor circle)
			)
			(primitives
				(gr_poly
					(pts
						(arc
							(start -0.1778 -0.2794)
							(mid -0.249642 -0.249642)
							(end -0.2794 -0.1778)
						)
						(arc
							(start -0.2794 0.1778)
							(mid -0.249642 0.249642)
							(end -0.1778 0.2794)
						)
						(arc
							(start 0.1778 0.2794)
							(mid 0.249642 0.249642)
							(end 0.2794 0.1778)
						)
						(arc
							(start 0.2794 -0.1778)
							(mid 0.249642 -0.249642)
							(end 0.1778 -0.2794)
						)
					)
					(width 0)
					(fill yes)
				)
			)
		)
	)
	(footprint ""
		(layer "F.Cu")
		(at 150.79472 -215.011 180)
		(property "Reference" "Q223"
			(at 0 0 180)
			(layer "F.SilkS")
			(hide yes)
			(effects
				(font
					(size 1.27 1.27)
				)
			)
		)
		(property "Value" "2N7002K-2-GP"
			(at 0.127 -8.9662 180)
			(unlocked yes)
			(layer "F.Fab")
			(hide yes)
			(effects
				(font
					(size 1.016 1.016)
					(thickness 0.1524)
				)
			)
		)
		(property "Device Type" "SOT23DGS2D4H44"
			(at 0.127 -10.4902 180)
			(unlocked yes)
			(layer "F.Fab")
			(hide yes)
			(effects
				(font
					(size 1.016 1.016)
					(thickness 0.1524)
				)
			)
		)
		(duplicate_pad_numbers_are_jumpers no)
		(fp_line
			(start 1.651 1.778)
			(end 1.651 -1.778)
			(stroke
				(width 0.1524)
				(type default)
			)
			(layer "F.SilkS")
		)
		(fp_line
			(start 1.651 -1.778)
			(end -1.651 -1.778)
			(stroke
				(width 0.1524)
				(type default)
			)
			(layer "F.SilkS")
		)
		(fp_line
			(start -1.651 1.778)
			(end 1.651 1.778)
			(stroke
				(width 0.1524)
				(type default)
			)
			(layer "F.SilkS")
		)
		(fp_line
			(start -1.651 -1.778)
			(end -1.651 1.778)
			(stroke
				(width 0.1524)
				(type default)
			)
			(layer "F.SilkS")
		)
		(fp_poly
			(pts
				(xy -1.778 1.8796) (xy -1.778 -1.8796) (xy 1.778 -1.8796) (xy 1.778 1.8796)
			)
			(stroke
				(width 0)
				(type default)
			)
			(fill no)
			(layer "F.CrtYd")
		)
		(fp_poly
			(pts
				(xy -1.778 1.8796) (xy -1.778 -1.8796) (xy 1.778 -1.8796) (xy 1.778 1.8796)
			)
			(stroke
				(width 0)
				(type default)
			)
			(fill no)
			(layer "F.Fab")
		)
		(pad "D" smd custom
			(at 0 -0.9525 180)
			(size 0.1905 0.1905)
			(layers "F.Cu" "F.Mask" "F.Paste")
			(net "FLT_HDD4_N")
			(options
				(clearance outline)
				(anchor circle)
			)
			(primitives
				(gr_poly
					(pts
						(arc
							(start -0.1778 0.5715)
							(mid -0.321484 0.511984)
							(end -0.381 0.3683)
						)
						(arc
							(start -0.381 -0.3683)
							(mid -0.321484 -0.511984)
							(end -0.1778 -0.5715)
						)
						(arc
							(start 0.1778 -0.5715)
							(mid 0.321484 -0.511984)
							(end 0.381 -0.3683)
						)
						(arc
							(start 0.381 0.3683)
							(mid 0.321484 0.511984)
							(end 0.1778 0.5715)
						)
					)
					(width 0)
					(fill yes)
				)
			)
		)
		(pad "G" smd custom
			(at -0.98425 0.9525 180)
			(size 0.1905 0.1905)
			(layers "F.Cu" "F.Mask" "F.Paste")
			(net "DRIVE_B_4_FLT_LED")
			(options
				(clearance outline)
				(anchor circle)
			)
			(primitives
				(gr_poly
					(pts
						(arc
							(start -0.1778 0.5715)
							(mid -0.321484 0.511984)
							(end -0.381 0.3683)
						)
						(arc
							(start -0.381 -0.3683)
							(mid -0.321484 -0.511984)
							(end -0.1778 -0.5715)
						)
						(arc
							(start 0.1778 -0.5715)
							(mid 0.321484 -0.511984)
							(end 0.381 -0.3683)
						)
						(arc
							(start 0.381 0.3683)
							(mid 0.321484 0.511984)
							(end 0.1778 0.5715)
						)
					)
					(width 0)
					(fill yes)
				)
			)
		)
		(pad "S" smd custom
			(at 0.98425 0.9525 180)
			(size 0.1905 0.1905)
			(layers "F.Cu" "F.Mask" "F.Paste")
			(net "GND")
			(options
				(clearance outline)
				(anchor circle)
			)
			(primitives
				(gr_poly
					(pts
						(arc
							(start -0.1778 0.5715)
							(mid -0.321484 0.511984)
							(end -0.381 0.3683)
						)
						(arc
							(start -0.381 -0.3683)
							(mid -0.321484 -0.511984)
							(end -0.1778 -0.5715)
						)
						(arc
							(start 0.1778 -0.5715)
							(mid 0.321484 -0.511984)
							(end 0.381 -0.3683)
						)
						(arc
							(start 0.381 0.3683)
							(mid 0.321484 0.511984)
							(end 0.1778 0.5715)
						)
					)
					(width 0)
					(fill yes)
				)
			)
		)
	)
)
